(kicad_pcb
	(version 20260206)
	(generator "pcbnew")
	(generator_version "10.0")
	(general
		(thickness 1.6)
		(legacy_teardrops no)
	)
	(paper "A4")
	(title_block
		(title "03242023_DA0F0TMBIJ0_F0T_Motherboard_J_brd_V01_OCP.brd")
		(comment 1 "Grand Teton / footprints 2804-2810 of 6105")
	)
	(layers
		(0 "F.Cu" signal "TOP")
		(4 "In1.Cu" signal "GND")
		(6 "In2.Cu" signal "IN1")
		(8 "In3.Cu" signal "GND1")
		(10 "In4.Cu" signal "IN2")
		(12 "In5.Cu" signal "GND2")
		(14 "In6.Cu" signal "IN3")
		(16 "In7.Cu" signal "GND3")
		(18 "In8.Cu" signal "VCC")
		(20 "In9.Cu" signal "VCC1")
		(22 "In10.Cu" signal "GND4")
		(24 "In11.Cu" signal "IN4")
		(26 "In12.Cu" signal "GND5")
		(28 "In13.Cu" signal "IN5")
		(30 "In14.Cu" signal "GND6")
		(32 "In15.Cu" signal "IN6")
		(34 "In16.Cu" signal "GND7")
		(2 "B.Cu" signal "BOTTOM")
		(9 "F.Adhes" user "F.Adhesive")
		(11 "B.Adhes" user "B.Adhesive")
		(13 "F.Paste" user "Package Geometry/Pastemask Top")
		(15 "B.Paste" user "Package Geometry/Pastemask Bottom")
		(5 "F.SilkS" user "Ref Des/Silkscreen Top")
		(7 "B.SilkS" user "Ref Des/Silkscreen Bottom")
		(1 "F.Mask" user "Board Geometry/Soldermask Top")
		(3 "B.Mask" user "Board Geometry/Soldermask Bottom")
		(17 "Dwgs.User" user "User.Drawings")
		(19 "Cmts.User" user "User.Comments")
		(21 "Eco1.User" user "User.Eco1")
		(23 "Eco2.User" user "User.Eco2")
		(25 "Edge.Cuts" user "Board Geometry/Outline")
		(27 "Margin" user)
		(31 "F.CrtYd" user "Package Geometry/Place Bound Top")
		(29 "B.CrtYd" user "Package Geometry/Place Bound Bottom")
		(35 "F.Fab" user "Ref Des/Assembly Top")
		(33 "B.Fab" user "Ref Des/Assembly Bottom")
	)
	(footprint ""
		(layer "F.Cu")
		(at 118.849902 -407.335228 180)
		(property "Reference" "R2830"
			(at 0 0 180)
			(layer "F.SilkS")
			(hide yes)
			(effects
				(font
					(size 1.27 1.27)
				)
			)
		)
		(property "Value" ""
			(at 0 0 180)
			(layer "F.Fab")
			(effects
				(font
					(size 1.27 1.27)
				)
			)
		)
		(duplicate_pad_numbers_are_jumpers no)
		(fp_line
			(start 0.7874 0.4064)
			(end -0.7874 0.4064)
			(stroke
				(width 0.1524)
				(type default)
			)
			(layer "F.SilkS")
		)
		(fp_line
			(start 0.7874 -0.4064)
			(end 0.7874 0.4064)
			(stroke
				(width 0.1524)
				(type default)
			)
			(layer "F.SilkS")
		)
		(fp_line
			(start -0.7874 0.4064)
			(end -0.7874 -0.4064)
			(stroke
				(width 0.1524)
				(type default)
			)
			(layer "F.SilkS")
		)
		(fp_line
			(start -0.7874 -0.4064)
			(end 0.7874 -0.4064)
			(stroke
				(width 0.1524)
				(type default)
			)
			(layer "F.SilkS")
		)
		(fp_line
			(start 0.67945 0.3048)
			(end 0.120396 0.3048)
			(stroke
				(width 0.1)
				(type default)
			)
			(layer "F.Fab")
		)
		(fp_line
			(start 0.67945 -0.3048)
			(end 0.67945 0.3048)
			(stroke
				(width 0.1)
				(type default)
			)
			(layer "F.Fab")
		)
		(fp_line
			(start 0.12065 -0.2794)
			(end 0.12065 -0.3048)
			(stroke
				(width 0.1)
				(type default)
			)
			(layer "F.Fab")
		)
		(fp_line
			(start 0.12065 -0.3048)
			(end 0.67945 -0.3048)
			(stroke
				(width 0.1)
				(type default)
			)
			(layer "F.Fab")
		)
		(fp_line
			(start 0.120396 0.3048)
			(end 0.120396 0.2794)
			(stroke
				(width 0.1)
				(type default)
			)
			(layer "F.Fab")
		)
		(fp_line
			(start 0.120396 0.2794)
			(end -0.12065 0.2794)
			(stroke
				(width 0.1)
				(type default)
			)
			(layer "F.Fab")
		)
		(fp_line
			(start -0.12065 0.3048)
			(end -0.67945 0.3048)
			(stroke
				(width 0.1)
				(type default)
			)
			(layer "F.Fab")
		)
		(fp_line
			(start -0.12065 0.2794)
			(end -0.12065 0.3048)
			(stroke
				(width 0.1)
				(type default)
			)
			(layer "F.Fab")
		)
		(fp_line
			(start -0.12065 -0.2794)
			(end 0.12065 -0.2794)
			(stroke
				(width 0.1)
				(type default)
			)
			(layer "F.Fab")
		)
		(fp_line
			(start -0.12065 -0.305054)
			(end -0.12065 -0.2794)
			(stroke
				(width 0.1)
				(type default)
			)
			(layer "F.Fab")
		)
		(fp_line
			(start -0.67945 0.3048)
			(end -0.67945 -0.305054)
			(stroke
				(width 0.1)
				(type default)
			)
			(layer "F.Fab")
		)
		(fp_line
			(start -0.67945 -0.305054)
			(end -0.12065 -0.305054)
			(stroke
				(width 0.1)
				(type default)
			)
			(layer "F.Fab")
		)
		(pad "1" smd circle
			(at -0.40005 0 180)
			(size 0 0)
			(layers "F.Cu" "F.Mask" "F.Paste")
			(net "P3V3_AUX")
		)
		(pad "2" smd circle
			(at 0.40005 0 180)
			(size 0 0)
			(layers "F.Cu" "F.Mask" "F.Paste")
			(net "BIC_MONITER")
		)
	)
	(footprint ""
		(layer "F.Cu")
		(at 29.977334 -169.000678 90)
		(property "Reference" "PC392"
			(at 0 0 90)
			(layer "F.SilkS")
			(hide yes)
			(effects
				(font
					(size 1.27 1.27)
				)
			)
		)
		(property "Value" ""
			(at 0 0 90)
			(layer "F.Fab")
			(effects
				(font
					(size 1.27 1.27)
				)
			)
		)
		(duplicate_pad_numbers_are_jumpers no)
		(fp_line
			(start 0.7874 -0.4064)
			(end 0.7874 0.4064)
			(stroke
				(width 0.1524)
				(type default)
			)
			(layer "F.SilkS")
		)
		(fp_line
			(start -0.7874 -0.4064)
			(end 0.7874 -0.4064)
			(stroke
				(width 0.1524)
				(type default)
			)
			(layer "F.SilkS")
		)
		(fp_line
			(start 0.7874 0.4064)
			(end -0.7874 0.4064)
			(stroke
				(width 0.1524)
				(type default)
			)
			(layer "F.SilkS")
		)
		(fp_line
			(start -0.7874 0.4064)
			(end -0.7874 -0.4064)
			(stroke
				(width 0.1524)
				(type default)
			)
			(layer "F.SilkS")
		)
		(fp_line
			(start -0.12065 -0.305054)
			(end -0.12065 -0.2794)
			(stroke
				(width 0.1)
				(type default)
			)
			(layer "F.Fab")
		)
		(fp_line
			(start -0.67945 -0.305054)
			(end -0.12065 -0.305054)
			(stroke
				(width 0.1)
				(type default)
			)
			(layer "F.Fab")
		)
		(fp_line
			(start 0.67945 -0.3048)
			(end 0.67945 0.3048)
			(stroke
				(width 0.1)
				(type default)
			)
			(layer "F.Fab")
		)
		(fp_line
			(start 0.12065 -0.3048)
			(end 0.67945 -0.3048)
			(stroke
				(width 0.1)
				(type default)
			)
			(layer "F.Fab")
		)
		(fp_line
			(start 0.12065 -0.2794)
			(end 0.12065 -0.3048)
			(stroke
				(width 0.1)
				(type default)
			)
			(layer "F.Fab")
		)
		(fp_line
			(start -0.12065 -0.2794)
			(end 0.12065 -0.2794)
			(stroke
				(width 0.1)
				(type default)
			)
			(layer "F.Fab")
		)
		(fp_line
			(start 0.120396 0.2794)
			(end -0.12065 0.2794)
			(stroke
				(width 0.1)
				(type default)
			)
			(layer "F.Fab")
		)
		(fp_line
			(start -0.12065 0.2794)
			(end -0.12065 0.3048)
			(stroke
				(width 0.1)
				(type default)
			)
			(layer "F.Fab")
		)
		(fp_line
			(start 0.67945 0.3048)
			(end 0.120396 0.3048)
			(stroke
				(width 0.1)
				(type default)
			)
			(layer "F.Fab")
		)
		(fp_line
			(start 0.120396 0.3048)
			(end 0.120396 0.2794)
			(stroke
				(width 0.1)
				(type default)
			)
			(layer "F.Fab")
		)
		(fp_line
			(start -0.12065 0.3048)
			(end -0.67945 0.3048)
			(stroke
				(width 0.1)
				(type default)
			)
			(layer "F.Fab")
		)
		(fp_line
			(start -0.67945 0.3048)
			(end -0.67945 -0.305054)
			(stroke
				(width 0.1)
				(type default)
			)
			(layer "F.Fab")
		)
		(pad "1" smd circle
			(at -0.40005 0 90)
			(size 0 0)
			(layers "F.Cu" "F.Mask" "F.Paste")
			(net "PVCCD_HV_CPU1_VREF")
		)
		(pad "2" smd circle
			(at 0.40005 0 90)
			(size 0 0)
			(layers "F.Cu" "F.Mask" "F.Paste")
			(net "GND")
		)
	)
	(footprint ""
		(layer "F.Cu")
		(at 214.61349 -23.304754 90)
		(property "Reference" "R1138"
			(at 0 0 90)
			(layer "F.SilkS")
			(hide yes)
			(effects
				(font
					(size 1.27 1.27)
				)
			)
		)
		(property "Value" ""
			(at 0 0 90)
			(layer "F.Fab")
			(effects
				(font
					(size 1.27 1.27)
				)
			)
		)
		(duplicate_pad_numbers_are_jumpers no)
		(fp_line
			(start 0.7874 -0.4064)
			(end 0.7874 0.4064)
			(stroke
				(width 0.1524)
				(type default)
			)
			(layer "F.SilkS")
		)
		(fp_line
			(start -0.7874 -0.4064)
			(end 0.7874 -0.4064)
			(stroke
				(width 0.1524)
				(type default)
			)
			(layer "F.SilkS")
		)
		(fp_line
			(start 0.7874 0.4064)
			(end -0.7874 0.4064)
			(stroke
				(width 0.1524)
				(type default)
			)
			(layer "F.SilkS")
		)
		(fp_line
			(start -0.7874 0.4064)
			(end -0.7874 -0.4064)
			(stroke
				(width 0.1524)
				(type default)
			)
			(layer "F.SilkS")
		)
		(fp_line
			(start -0.12065 -0.305054)
			(end -0.12065 -0.2794)
			(stroke
				(width 0.1)
				(type default)
			)
			(layer "F.Fab")
		)
		(fp_line
			(start -0.67945 -0.305054)
			(end -0.12065 -0.305054)
			(stroke
				(width 0.1)
				(type default)
			)
			(layer "F.Fab")
		)
		(fp_line
			(start 0.67945 -0.3048)
			(end 0.67945 0.3048)
			(stroke
				(width 0.1)
				(type default)
			)
			(layer "F.Fab")
		)
		(fp_line
			(start 0.12065 -0.3048)
			(end 0.67945 -0.3048)
			(stroke
				(width 0.1)
				(type default)
			)
			(layer "F.Fab")
		)
		(fp_line
			(start 0.12065 -0.2794)
			(end 0.12065 -0.3048)
			(stroke
				(width 0.1)
				(type default)
			)
			(layer "F.Fab")
		)
		(fp_line
			(start -0.12065 -0.2794)
			(end 0.12065 -0.2794)
			(stroke
				(width 0.1)
				(type default)
			)
			(layer "F.Fab")
		)
		(fp_line
			(start 0.120396 0.2794)
			(end -0.12065 0.2794)
			(stroke
				(width 0.1)
				(type default)
			)
			(layer "F.Fab")
		)
		(fp_line
			(start -0.12065 0.2794)
			(end -0.12065 0.3048)
			(stroke
				(width 0.1)
				(type default)
			)
			(layer "F.Fab")
		)
		(fp_line
			(start 0.67945 0.3048)
			(end 0.120396 0.3048)
			(stroke
				(width 0.1)
				(type default)
			)
			(layer "F.Fab")
		)
		(fp_line
			(start 0.120396 0.3048)
			(end 0.120396 0.2794)
			(stroke
				(width 0.1)
				(type default)
			)
			(layer "F.Fab")
		)
		(fp_line
			(start -0.12065 0.3048)
			(end -0.67945 0.3048)
			(stroke
				(width 0.1)
				(type default)
			)
			(layer "F.Fab")
		)
		(fp_line
			(start -0.67945 0.3048)
			(end -0.67945 -0.305054)
			(stroke
				(width 0.1)
				(type default)
			)
			(layer "F.Fab")
		)
		(pad "1" smd circle
			(at -0.40005 0 90)
			(size 0 0)
			(layers "F.Cu" "F.Mask" "F.Paste")
			(net "P3V3_AUX")
		)
		(pad "2" smd circle
			(at 0.40005 0 90)
			(size 0 0)
			(layers "F.Cu" "F.Mask" "F.Paste")
			(net "CLK_50M_EN")
		)
	)
	(footprint ""
		(layer "F.Cu")
		(at 71.79056 -56.159908 -90)
		(property "Reference" "PC2173"
			(at 0 0 270)
			(layer "F.SilkS")
			(hide yes)
			(effects
				(font
					(size 1.27 1.27)
				)
			)
		)
		(property "Value" ""
			(at 0 0 270)
			(layer "F.Fab")
			(effects
				(font
					(size 1.27 1.27)
				)
			)
		)
		(duplicate_pad_numbers_are_jumpers no)
		(fp_line
			(start -1.524 0.762)
			(end -1.524 -0.762)
			(stroke
				(width 0.1524)
				(type default)
			)
			(layer "F.SilkS")
		)
		(fp_line
			(start 1.524 0.762)
			(end -1.524 0.762)
			(stroke
				(width 0.1524)
				(type default)
			)
			(layer "F.SilkS")
		)
		(fp_line
			(start -1.524 -0.762)
			(end 1.524 -0.762)
			(stroke
				(width 0.1524)
				(type default)
			)
			(layer "F.SilkS")
		)
		(fp_line
			(start 1.524 -0.762)
			(end 1.524 0.762)
			(stroke
				(width 0.1524)
				(type default)
			)
			(layer "F.SilkS")
		)
		(fp_line
			(start -1.1049 0.724916)
			(end 1.1049 0.724916)
			(stroke
				(width 0.1)
				(type default)
			)
			(layer "F.Fab")
		)
		(fp_line
			(start 1.1049 0.724916)
			(end 1.1049 -0.724916)
			(stroke
				(width 0.1)
				(type default)
			)
			(layer "F.Fab")
		)
		(fp_line
			(start -1.1049 -0.724916)
			(end -1.1049 0.724916)
			(stroke
				(width 0.1)
				(type default)
			)
			(layer "F.Fab")
		)
		(fp_line
			(start 1.1049 -0.724916)
			(end -1.1049 -0.724916)
			(stroke
				(width 0.1)
				(type default)
			)
			(layer "F.Fab")
		)
		(pad "1" smd rect
			(at -0.889 0 90)
			(size 1.016 1.27)
			(layers "F.Cu" "F.Mask" "F.Paste")
			(net "P3V3_OCP_V3_2_R")
		)
		(pad "2" smd rect
			(at 0.889 0 90)
			(size 1.016 1.27)
			(layers "F.Cu" "F.Mask" "F.Paste")
			(net "GND")
		)
	)
	(footprint ""
		(layer "F.Cu")
		(at 22.809454 -114.431826 180)
		(property "Reference" "R3690"
			(at 0 0 180)
			(layer "F.SilkS")
			(hide yes)
			(effects
				(font
					(size 1.27 1.27)
				)
			)
		)
		(property "Value" ""
			(at 0 0 180)
			(layer "F.Fab")
			(effects
				(font
					(size 1.27 1.27)
				)
			)
		)
		(duplicate_pad_numbers_are_jumpers no)
		(fp_line
			(start 0.7874 0.4064)
			(end -0.7874 0.4064)
			(stroke
				(width 0.1524)
				(type default)
			)
			(layer "F.SilkS")
		)
		(fp_line
			(start 0.7874 -0.4064)
			(end 0.7874 0.4064)
			(stroke
				(width 0.1524)
				(type default)
			)
			(layer "F.SilkS")
		)
		(fp_line
			(start -0.7874 0.4064)
			(end -0.7874 -0.4064)
			(stroke
				(width 0.1524)
				(type default)
			)
			(layer "F.SilkS")
		)
		(fp_line
			(start -0.7874 -0.4064)
			(end 0.7874 -0.4064)
			(stroke
				(width 0.1524)
				(type default)
			)
			(layer "F.SilkS")
		)
		(fp_line
			(start 0.67945 0.3048)
			(end 0.120396 0.3048)
			(stroke
				(width 0.1)
				(type default)
			)
			(layer "F.Fab")
		)
		(fp_line
			(start 0.67945 -0.3048)
			(end 0.67945 0.3048)
			(stroke
				(width 0.1)
				(type default)
			)
			(layer "F.Fab")
		)
		(fp_line
			(start 0.12065 -0.2794)
			(end 0.12065 -0.3048)
			(stroke
				(width 0.1)
				(type default)
			)
			(layer "F.Fab")
		)
		(fp_line
			(start 0.12065 -0.3048)
			(end 0.67945 -0.3048)
			(stroke
				(width 0.1)
				(type default)
			)
			(layer "F.Fab")
		)
		(fp_line
			(start 0.120396 0.3048)
			(end 0.120396 0.2794)
			(stroke
				(width 0.1)
				(type default)
			)
			(layer "F.Fab")
		)
		(fp_line
			(start 0.120396 0.2794)
			(end -0.12065 0.2794)
			(stroke
				(width 0.1)
				(type default)
			)
			(layer "F.Fab")
		)
		(fp_line
			(start -0.12065 0.3048)
			(end -0.67945 0.3048)
			(stroke
				(width 0.1)
				(type default)
			)
			(layer "F.Fab")
		)
		(fp_line
			(start -0.12065 0.2794)
			(end -0.12065 0.3048)
			(stroke
				(width 0.1)
				(type default)
			)
			(layer "F.Fab")
		)
		(fp_line
			(start -0.12065 -0.2794)
			(end 0.12065 -0.2794)
			(stroke
				(width 0.1)
				(type default)
			)
			(layer "F.Fab")
		)
		(fp_line
			(start -0.12065 -0.305054)
			(end -0.12065 -0.2794)
			(stroke
				(width 0.1)
				(type default)
			)
			(layer "F.Fab")
		)
		(fp_line
			(start -0.67945 0.3048)
			(end -0.67945 -0.305054)
			(stroke
				(width 0.1)
				(type default)
			)
			(layer "F.Fab")
		)
		(fp_line
			(start -0.67945 -0.305054)
			(end -0.12065 -0.305054)
			(stroke
				(width 0.1)
				(type default)
			)
			(layer "F.Fab")
		)
		(pad "1" smd circle
			(at -0.40005 0 180)
			(size 0 0)
			(layers "F.Cu" "F.Mask" "F.Paste")
			(net "ADC128_VREF")
		)
		(pad "2" smd circle
			(at 0.40005 0 180)
			(size 0 0)
			(layers "F.Cu" "F.Mask" "F.Paste")
			(net "GND")
		)
	)
	(footprint ""
		(layer "F.Cu")
		(at 463.562954 -93.396054)
		(property "Reference" "R3232"
			(at 0 0 0)
			(layer "F.SilkS")
			(hide yes)
			(effects
				(font
					(size 1.27 1.27)
				)
			)
		)
		(property "Value" ""
			(at 0 0 0)
			(layer "F.Fab")
			(effects
				(font
					(size 1.27 1.27)
				)
			)
		)
		(duplicate_pad_numbers_are_jumpers no)
		(fp_line
			(start -0.7874 -0.4064)
			(end 0.7874 -0.4064)
			(stroke
				(width 0.1524)
				(type default)
			)
			(layer "F.SilkS")
		)
		(fp_line
			(start -0.7874 0.4064)
			(end -0.7874 -0.4064)
			(stroke
				(width 0.1524)
				(type default)
			)
			(layer "F.SilkS")
		)
		(fp_line
			(start 0.7874 -0.4064)
			(end 0.7874 0.4064)
			(stroke
				(width 0.1524)
				(type default)
			)
			(layer "F.SilkS")
		)
		(fp_line
			(start 0.7874 0.4064)
			(end -0.7874 0.4064)
			(stroke
				(width 0.1524)
				(type default)
			)
			(layer "F.SilkS")
		)
		(fp_line
			(start -0.67945 -0.305054)
			(end -0.12065 -0.305054)
			(stroke
				(width 0.1)
				(type default)
			)
			(layer "F.Fab")
		)
		(fp_line
			(start -0.67945 0.3048)
			(end -0.67945 -0.305054)
			(stroke
				(width 0.1)
				(type default)
			)
			(layer "F.Fab")
		)
		(fp_line
			(start -0.12065 -0.305054)
			(end -0.12065 -0.2794)
			(stroke
				(width 0.1)
				(type default)
			)
			(layer "F.Fab")
		)
		(fp_line
			(start -0.12065 -0.2794)
			(end 0.12065 -0.2794)
			(stroke
				(width 0.1)
				(type default)
			)
			(layer "F.Fab")
		)
		(fp_line
			(start -0.12065 0.2794)
			(end -0.12065 0.3048)
			(stroke
				(width 0.1)
				(type default)
			)
			(layer "F.Fab")
		)
		(fp_line
			(start -0.12065 0.3048)
			(end -0.67945 0.3048)
			(stroke
				(width 0.1)
				(type default)
			)
			(layer "F.Fab")
		)
		(fp_line
			(start 0.120396 0.2794)
			(end -0.12065 0.2794)
			(stroke
				(width 0.1)
				(type default)
			)
			(layer "F.Fab")
		)
		(fp_line
			(start 0.120396 0.3048)
			(end 0.120396 0.2794)
			(stroke
				(width 0.1)
				(type default)
			)
			(layer "F.Fab")
		)
		(fp_line
			(start 0.12065 -0.3048)
			(end 0.67945 -0.3048)
			(stroke
				(width 0.1)
				(type default)
			)
			(layer "F.Fab")
		)
		(fp_line
			(start 0.12065 -0.2794)
			(end 0.12065 -0.3048)
			(stroke
				(width 0.1)
				(type default)
			)
			(layer "F.Fab")
		)
		(fp_line
			(start 0.67945 -0.3048)
			(end 0.67945 0.3048)
			(stroke
				(width 0.1)
				(type default)
			)
			(layer "F.Fab")
		)
		(fp_line
			(start 0.67945 0.3048)
			(end 0.120396 0.3048)
			(stroke
				(width 0.1)
				(type default)
			)
			(layer "F.Fab")
		)
		(pad "1" smd circle
			(at -0.40005 0)
			(size 0 0)
			(layers "F.Cu" "F.Mask" "F.Paste")
			(net "RST_HP_OCP_SFF_R_N")
		)
		(pad "2" smd circle
			(at 0.40005 0)
			(size 0 0)
			(layers "F.Cu" "F.Mask" "F.Paste")
			(net "GND")
		)
	)
	(footprint ""
		(layer "F.Cu")
		(at 255.493012 -76.222098 90)
		(property "Reference" "PC1215"
			(at 0 0 90)
			(layer "F.SilkS")
			(hide yes)
			(effects
				(font
					(size 1.27 1.27)
				)
			)
		)
		(property "Value" ""
			(at 0 0 90)
			(layer "F.Fab")
			(effects
				(font
					(size 1.27 1.27)
				)
			)
		)
		(duplicate_pad_numbers_are_jumpers no)
		(fp_line
			(start 2.750058 -2.750058)
			(end -1.988058 -2.750058)
			(stroke
				(width 0.1524)
				(type default)
			)
			(layer "F.SilkS")
		)
		(fp_line
			(start -1.988058 -2.750058)
			(end -2.750058 -1.988058)
			(stroke
				(width 0.1524)
				(type default)
			)
			(layer "F.SilkS")
		)
		(fp_line
			(start -2.750058 -1.988058)
			(end -2.750058 -0.9398)
			(stroke
				(width 0.1524)
				(type default)
			)
			(layer "F.SilkS")
		)
		(fp_line
			(start 2.750058 -0.9398)
			(end 2.750058 -2.750058)
			(stroke
				(width 0.1524)
				(type default)
			)
			(layer "F.SilkS")
		)
		(fp_line
			(start -2.750058 0.9398)
			(end -2.750058 1.988058)
			(stroke
				(width 0.1524)
				(type default)
			)
			(layer "F.SilkS")
		)
		(fp_line
			(start -2.750058 1.988058)
			(end -1.988058 2.750058)
			(stroke
				(width 0.1524)
				(type default)
			)
			(layer "F.SilkS")
		)
		(fp_line
			(start 2.750058 2.750058)
			(end 2.750058 0.9398)
			(stroke
				(width 0.1524)
				(type default)
			)
			(layer "F.SilkS")
		)
		(fp_line
			(start -1.988058 2.750058)
			(end 2.750058 2.750058)
			(stroke
				(width 0.1524)
				(type default)
			)
			(layer "F.SilkS")
		)
		(fp_line
			(start 2.750058 -2.750058)
			(end -2.750058 -2.750058)
			(stroke
				(width 0.1)
				(type default)
			)
			(layer "F.Fab")
		)
		(fp_line
			(start -2.750058 -2.750058)
			(end -2.750058 2.750058)
			(stroke
				(width 0.1)
				(type default)
			)
			(layer "F.Fab")
		)
		(fp_line
			(start 2.750058 2.750058)
			(end 2.750058 -2.750058)
			(stroke
				(width 0.1)
				(type default)
			)
			(layer "F.Fab")
		)
		(fp_line
			(start -2.750058 2.750058)
			(end 2.750058 2.750058)
			(stroke
				(width 0.1)
				(type default)
			)
			(layer "F.Fab")
		)
		(pad "1" smd rect
			(at -2.199894 0 180)
			(size 1.6002 3.0226)
			(layers "F.Cu" "F.Mask" "F.Paste")
			(net "SW_P12V_AUX_P1V05_PCH_AUX_FLT")
		)
		(pad "2" smd rect
			(at 2.199894 0 180)
			(size 1.6002 3.0226)
			(layers "F.Cu" "F.Mask" "F.Paste")
			(net "GND")
		)
	)
)
